# SCM (Grand Teton) — schematic netlist excerpt (pin names and nets, part order shuffled) for the footprints in the layout excerpt that follows; sources: Cadence DE-HDL packaged netlist, KiCad conversion of 12092022_DA0F0TMDCD0_F0T_Management_Board_D_brd_V3_OCP.brd

R711  Q_RES  0 5% EMPTY  pkg 0402LF  page 22 : A = PWRGD_PSU_AC_PWROK ; B = PWRGD_P1V0_AUX_DELAY

U54  74LVC1G74DP  IC  pkg TSSOP8_0-65_3X3  page 25
  CP  = FLASH_LATCH_CP
  D  = FLASH_LATCH_D
  Q_N  = FLASH_LATCH_Q_N_R
  GND  = GND
  Q  = NC_U54_P1
  RD_N  = RD_N
  SD_N  = FM_FLASH_LATCH_N
  VCC  = P3V3_AUX

(kicad_pcb
	(version 20260206)
	(generator "pcbnew")
	(generator_version "10.0")
	(general
		(thickness 1.6)
		(legacy_teardrops no)
	)
	(paper "A4")
	(title_block
		(title "12092022_DA0F0TMDCD0_F0T_Management_Board_D_brd_V3_OCP.brd")
		(comment 1 "Grand Teton / footprints 506-507 of 1440")
	)
	(layers
		(0 "F.Cu" signal "TOP")
		(4 "In1.Cu" signal "GND")
		(6 "In2.Cu" signal "IN1")
		(8 "In3.Cu" signal "GND1")
		(10 "In4.Cu" signal "IN2")
		(12 "In5.Cu" signal "VCC")
		(14 "In6.Cu" signal "VCC1")
		(16 "In7.Cu" signal "IN3")
		(18 "In8.Cu" signal "GND2")
		(20 "In9.Cu" signal "IN4")
		(22 "In10.Cu" signal "GND3")
		(2 "B.Cu" signal "BOTTOM")
		(9 "F.Adhes" user "F.Adhesive")
		(11 "B.Adhes" user "B.Adhesive")
		(13 "F.Paste" user "Package Geometry/Pastemask Top")
		(15 "B.Paste" user "Package Geometry/Pastemask Bottom")
		(5 "F.SilkS" user "Ref Des/Silkscreen Top")
		(7 "B.SilkS" user "Ref Des/Silkscreen Bottom")
		(1 "F.Mask" user "Board Geometry/Soldermask Top")
		(3 "B.Mask" user "Board Geometry/Soldermask Bottom")
		(17 "Dwgs.User" user "User.Drawings")
		(19 "Cmts.User" user "User.Comments")
		(21 "Eco1.User" user "User.Eco1")
		(23 "Eco2.User" user "User.Eco2")
		(25 "Edge.Cuts" user "Board Geometry/Outline")
		(27 "Margin" user)
		(31 "F.CrtYd" user "Package Geometry/Place Bound Top")
		(29 "B.CrtYd" user "Package Geometry/Place Bound Bottom")
		(35 "F.Fab" user "Ref Des/Assembly Top")
		(33 "B.Fab" user "Ref Des/Assembly Bottom")
	)
	(footprint ""
		(layer "F.Cu")
		(at 51.816 -76.3524 180)
		(property "Reference" "U54"
			(at 1.0414 -2.23647 0)
			(unlocked yes)
			(layer "F.SilkS")
			(effects
				(font
					(size 0.7874 0.5842)
					(thickness 0.1524)
				)
				(justify left)
			)
		)
		(property "Value" ""
			(at 0 0 180)
			(layer "F.Fab")
			(effects
				(font
					(size 1.27 1.27)
				)
			)
		)
		(duplicate_pad_numbers_are_jumpers no)
		(fp_line
			(start 1.207008 1.549908)
			(end 1.207008 -1.549908)
			(stroke
				(width 0.1524)
				(type default)
			)
			(layer "F.SilkS")
		)
		(fp_line
			(start 1.207008 -1.549908)
			(end 0.762508 -1.549908)
			(stroke
				(width 0.1524)
				(type default)
			)
			(layer "F.SilkS")
		)
		(fp_line
			(start 0.762508 -1.549908)
			(end 0 -0.635)
			(stroke
				(width 0.1524)
				(type default)
			)
			(layer "F.SilkS")
		)
		(fp_line
			(start 0 -0.635)
			(end -0.762508 -1.549908)
			(stroke
				(width 0.1524)
				(type default)
			)
			(layer "F.SilkS")
		)
		(fp_line
			(start -0.762508 -1.549908)
			(end -1.207008 -1.549908)
			(stroke
				(width 0.1524)
				(type default)
			)
			(layer "F.SilkS")
		)
		(fp_line
			(start -1.207008 1.549908)
			(end 1.207008 1.549908)
			(stroke
				(width 0.1524)
				(type default)
			)
			(layer "F.SilkS")
		)
		(fp_line
			(start -1.207008 -1.549908)
			(end -1.207008 1.549908)
			(stroke
				(width 0.1524)
				(type default)
			)
			(layer "F.SilkS")
		)
		(fp_poly
			(pts
				(xy -2.699258 -2.852166) (xy -3.41757 -2.1336) (xy -2.340102 -1.774444)
			)
			(stroke
				(width 0)
				(type default)
			)
			(fill yes)
			(layer "F.SilkS")
		)
		(fp_line
			(start 1.549908 1.549908)
			(end 1.549908 -1.549908)
			(stroke
				(width 0.1)
				(type default)
			)
			(layer "F.Fab")
		)
		(fp_line
			(start 1.549908 -1.549908)
			(end -1.549908 -1.549908)
			(stroke
				(width 0.1)
				(type default)
			)
			(layer "F.Fab")
		)
		(fp_line
			(start -1.549908 1.549908)
			(end 1.549908 1.549908)
			(stroke
				(width 0.1)
				(type default)
			)
			(layer "F.Fab")
		)
		(fp_line
			(start -1.549908 -1.549908)
			(end -1.549908 1.549908)
			(stroke
				(width 0.1)
				(type default)
			)
			(layer "F.Fab")
		)
		(fp_poly
			(pts
				(xy -3.4036 -1.53289) (xy -3.4036 -0.51689) (xy -2.3876 -1.02489)
			)
			(stroke
				(width 0)
				(type default)
			)
			(fill yes)
			(layer "F.Fab")
		)
		(pad "1" smd rect
			(at -1.774952 -1.02489 90)
			(size 0.508 0.8636)
			(layers "F.Cu" "F.Mask" "F.Paste")
			(net "FLASH_LATCH_CP")
		)
		(pad "2" smd rect
			(at -1.774952 -0.32512 90)
			(size 0.4064 0.8636)
			(layers "F.Cu" "F.Mask" "F.Paste")
			(net "FLASH_LATCH_D")
		)
		(pad "3" smd rect
			(at -1.774952 0.32512 90)
			(size 0.4064 0.8636)
			(layers "F.Cu" "F.Mask" "F.Paste")
			(net "FLASH_LATCH_Q_N_R")
		)
		(pad "4" smd rect
			(at -1.774952 1.02489 90)
			(size 0.508 0.8636)
			(layers "F.Cu" "F.Mask" "F.Paste")
			(net "GND")
		)
		(pad "5" smd rect
			(at 1.774952 1.02489 90)
			(size 0.508 0.8636)
			(layers "F.Cu" "F.Mask" "F.Paste")
			(net "NC_U54_P1")
		)
		(pad "6" smd rect
			(at 1.774952 0.32512 90)
			(size 0.4064 0.8636)
			(layers "F.Cu" "F.Mask" "F.Paste")
			(net "RD_N")
		)
		(pad "7" smd rect
			(at 1.774952 -0.32512 90)
			(size 0.4064 0.8636)
			(layers "F.Cu" "F.Mask" "F.Paste")
			(net "FM_FLASH_LATCH_N")
		)
		(pad "8" smd rect
			(at 1.774952 -1.02489 90)
			(size 0.508 0.8636)
			(layers "F.Cu" "F.Mask" "F.Paste")
			(net "P3V3_AUX")
		)
	)
	(footprint ""
		(layer "F.Cu")
		(at 9.271 -85.852)
		(property "Reference" "R711"
			(at 0 0 0)
			(layer "F.SilkS")
			(hide yes)
			(effects
				(font
					(size 1.27 1.27)
				)
			)
		)
		(property "Value" ""
			(at 0 0 0)
			(layer "F.Fab")
			(effects
				(font
					(size 1.27 1.27)
				)
			)
		)
		(duplicate_pad_numbers_are_jumpers no)
		(fp_line
			(start -0.7874 -0.4064)
			(end 0.7874 -0.4064)
			(stroke
				(width 0.1524)
				(type default)
			)
			(layer "F.SilkS")
		)
		(fp_line
			(start -0.7874 0.4064)
			(end -0.7874 -0.4064)
			(stroke
				(width 0.1524)
				(type default)
			)
			(layer "F.SilkS")
		)
		(fp_line
			(start 0.7874 -0.4064)
			(end 0.7874 0.4064)
			(stroke
				(width 0.1524)
				(type default)
			)
			(layer "F.SilkS")
		)
		(fp_line
			(start 0.7874 0.4064)
			(end -0.7874 0.4064)
			(stroke
				(width 0.1524)
				(type default)
			)
			(layer "F.SilkS")
		)
		(fp_line
			(start -0.67945 -0.305054)
			(end -0.12065 -0.305054)
			(stroke
				(width 0.1)
				(type default)
			)
			(layer "F.Fab")
		)
		(fp_line
			(start -0.67945 0.3048)
			(end -0.67945 -0.305054)
			(stroke
				(width 0.1)
				(type default)
			)
			(layer "F.Fab")
		)
		(fp_line
			(start -0.12065 -0.305054)
			(end -0.12065 -0.2794)
			(stroke
				(width 0.1)
				(type default)
			)
			(layer "F.Fab")
		)
		(fp_line
			(start -0.12065 -0.2794)
			(end 0.12065 -0.2794)
			(stroke
				(width 0.1)
				(type default)
			)
			(layer "F.Fab")
		)
		(fp_line
			(start -0.12065 0.2794)
			(end -0.12065 0.3048)
			(stroke
				(width 0.1)
				(type default)
			)
			(layer "F.Fab")
		)
		(fp_line
			(start -0.12065 0.3048)
			(end -0.67945 0.3048)
			(stroke
				(width 0.1)
				(type default)
			)
			(layer "F.Fab")
		)
		(fp_line
			(start 0.120396 0.2794)
			(end -0.12065 0.2794)
			(stroke
				(width 0.1)
				(type default)
			)
			(layer "F.Fab")
		)
		(fp_line
			(start 0.120396 0.3048)
			(end 0.120396 0.2794)
			(stroke
				(width 0.1)
				(type default)
			)
			(layer "F.Fab")
		)
		(fp_line
			(start 0.12065 -0.3048)
			(end 0.67945 -0.3048)
			(stroke
				(width 0.1)
				(type default)
			)
			(layer "F.Fab")
		)
		(fp_line
			(start 0.12065 -0.2794)
			(end 0.12065 -0.3048)
			(stroke
				(width 0.1)
				(type default)
			)
			(layer "F.Fab")
		)
		(fp_line
			(start 0.67945 -0.3048)
			(end 0.67945 0.3048)
			(stroke
				(width 0.1)
				(type default)
			)
			(layer "F.Fab")
		)
		(fp_line
			(start 0.67945 0.3048)
			(end 0.120396 0.3048)
			(stroke
				(width 0.1)
				(type default)
			)
			(layer "F.Fab")
		)
		(pad "1" smd circle
			(at -0.40005 0)
			(size 0 0)
			(layers "F.Cu" "F.Mask" "F.Paste")
			(net "PWRGD_PSU_AC_PWROK")
		)
		(pad "2" smd circle
			(at 0.40005 0)
			(size 0 0)
			(layers "F.Cu" "F.Mask" "F.Paste")
			(net "PWRGD_P1V0_AUX_DELAY")
		)
	)
)
